FILE_TYPE = MACRO_DRAWING;
SET COLOR_WIRE YELLOW;
SET COLOR_PROP ORANGE;
SET COLOR_DOT WHITE;
SET COLOR_ARC YELLOW;
SET COLOR_BODY GREEN;
SET COLOR_NOTE PURPLE;
SET PROP_DISPLAY VALUE;
SET PAGE_NUMBER P62;
FORCEADD QUANTA_TITLE_BLOCK_C..1
(0 0);
FORCEPROP 1 LAST CUSTOM_TXT_CDS <NAME_2>
J 0
(-3175 50);
FORCEPROP 1 LAST CUSTOM_TXT_CDS <NAME_1>
J 0
(-3175 175);
FORCEPROP 1 LAST CUSTOM_TXT_CDS <Q_NUMBER>
J 0
(-1403 103);
DISPLAY 1.212766 (-1403 103);
FORCEPROP 1 LAST CUSTOM_TXT_CDS <Q_PROJ>
J 0
(-2382 102);
DISPLAY 1.212766 (-2382 102);
FORCEPROP 1 LAST CUSTOM_TXT_CDS <Q_REV>
J 0
(-184 103);
DISPLAY 1.212766 (-184 103);
FORCEPROP 1 LAST CUSTOM_TXT_CDS <CON_LAST_MODIFIED>
J 0
(-1885 15);
DISPLAY 0.978723 (-1885 15);
FORCEPROP 1 LAST CUSTOM_TXT_CDS <CON_PAGE_NUM> OF <CON_TOTAL_PAGES>
J 0
(-446 18);
DISPLAY 0.978723 (-446 18);
FORCEPROP 1 LAST Q_TITLE Blank
J 0
(-9366 26);
DISPLAY 2.446809 (-9366 26);
PAINT GREEN (-9366 26);
FORCEPROP 2 LAST PAGE_BORDER TRUE
J 0
(-7890 5250);
DISPLAY 0.638298 (-7890 5250);
PAINT PINK (-7890 5250);
DISPLAY INVISIBLE (-7890 5250);
FORCEPROP 2 LAST CDS_LIB pure_quanta
J 0
(0 0);
DISPLAY INVISIBLE (0 0);
FORCEPROP 1 LAST CDS_LMAN_SYM_OUTLINE -9475,6775,100,-125
J 0
(0 0);
DISPLAY 0.468085 (0 0);
PAINT GREEN (0 0);
DISPLAY INVISIBLE (0 0);
FORCEPROP 2 LAST CDS_XR_PAGE_TITLE CR-62 : @T6G_MB_LIB.T6G(SCH_1):PAGE62
J 0
(-7890 5250);
DISPLAY 0.638298 (-7890 5250);
PAINT PINK (-7890 5250);
DISPLAY INVISIBLE (-7890 5250);
FORCEPROP 2 LAST CUSTOM_TXT_CDS <XR_PAGE_TITLE>
J 0
(-7890 5250);
DISPLAY 0.638298 (-7890 5250);
PAINT PINK (-7890 5250);
DISPLAY INVISIBLE (-7890 5250);
FORCEPROP 1 LAST COMMENT_BODY TRUE
J 0
(12 -13);
DISPLAY 0.978723 (12 -13);
PAINT GREEN (12 -13);
DISPLAY INVISIBLE (12 -13);
FORCEPROP 1 LAST Q_DEPT BU9
J 1
(-3763 49);
DISPLAY 1.957447 (-3763 49);
PAINT GREEN (-3763 49);
DISPLAY INVISIBLE (-3763 49);
FORCEPROP 0 LAST CDS_CON_LAST_MODIFIED Thu Aug 24 10:13:55 2023
J 0
(-1885 15);
DISPLAY INVISIBLE (-1885 15);
QUIT
